# T6G (Grand Teton) — schematic netlist excerpt (pin names and nets, part order shuffled) for the footprints in the layout excerpt that follows; sources: Cadence DE-HDL packaged netlist, KiCad conversion of 04192023_DAF0TMB3IC0_F0TG_MB_C_brd_V02_OCP.brd

R865  Q_RES  20K 1% CHIP  pkg 0201LF  page 342 : A = RT_CPU1_P2_ADDR2 ; B = GND
R4576  Q_RES  0 5% EMPTY  pkg 0402LF  page 125 : A = GPU_3V3IO_RSVD5_FFU ; B = GPU_3V3IO_RSVD5_FFU_ISO
R1335  Q_RES  0 5% EMPTY  pkg 0402LF  page 159 : A = I3C_SPD_DDRAF_CPU1_BYPASS_SDA ; B = I3C_SPD_DDRAF_CPU1_SDA

(kicad_pcb
	(version 20260206)
	(generator "pcbnew")
	(generator_version "10.0")
	(general
		(thickness 1.6)
		(legacy_teardrops no)
	)
	(paper "A4")
	(title_block
		(title "04192023_DAF0TMB3IC0_F0TG_MB_C_brd_V02_OCP.brd")
		(comment 1 "Grand Teton / footprints 199-201 of 8354")
	)
	(layers
		(0 "F.Cu" signal "TOP")
		(4 "In1.Cu" signal "GND")
		(6 "In2.Cu" signal "IN1")
		(8 "In3.Cu" signal "GND1")
		(10 "In4.Cu" signal "IN2")
		(12 "In5.Cu" signal "GND2")
		(14 "In6.Cu" signal "IN3")
		(16 "In7.Cu" signal "GND3")
		(18 "In8.Cu" signal "VCC")
		(20 "In9.Cu" signal "VCC1")
		(22 "In10.Cu" signal "GND4")
		(24 "In11.Cu" signal "IN4")
		(26 "In12.Cu" signal "GND5")
		(28 "In13.Cu" signal "IN5")
		(30 "In14.Cu" signal "GND6")
		(32 "In15.Cu" signal "IN6")
		(34 "In16.Cu" signal "GND7")
		(2 "B.Cu" signal "BOTTOM")
		(9 "F.Adhes" user "F.Adhesive")
		(11 "B.Adhes" user "B.Adhesive")
		(13 "F.Paste" user "Package Geometry/Pastemask Top")
		(15 "B.Paste" user "Package Geometry/Pastemask Bottom")
		(5 "F.SilkS" user "Ref Des/Silkscreen Top")
		(7 "B.SilkS" user "Ref Des/Silkscreen Bottom")
		(1 "F.Mask" user "Board Geometry/Soldermask Top")
		(3 "B.Mask" user "Board Geometry/Soldermask Bottom")
		(17 "Dwgs.User" user "User.Drawings")
		(19 "Cmts.User" user "User.Comments")
		(21 "Eco1.User" user "User.Eco1")
		(23 "Eco2.User" user "User.Eco2")
		(25 "Edge.Cuts" user "Board Geometry/Outline")
		(27 "Margin" user)
		(31 "F.CrtYd" user "Package Geometry/Place Bound Top")
		(29 "B.CrtYd" user "Package Geometry/Place Bound Bottom")
		(35 "F.Fab" user "Ref Des/Assembly Top")
		(33 "B.Fab" user "Ref Des/Assembly Bottom")
	)
	(footprint ""
		(layer "F.Cu")
		(at 174.030894 -391.34288 180)
		(property "Reference" "R865"
			(at 0 0 180)
			(layer "F.SilkS")
			(hide yes)
			(effects
				(font
					(size 1.27 1.27)
				)
			)
		)
		(property "Value" ""
			(at 0 0 180)
			(layer "F.Fab")
			(effects
				(font
					(size 1.27 1.27)
				)
			)
		)
		(duplicate_pad_numbers_are_jumpers no)
		(fp_line
			(start 0.32512 0.175006)
			(end -0.32512 0.175006)
			(stroke
				(width 0.1)
				(type default)
			)
			(layer "F.Fab")
		)
		(fp_line
			(start 0.32512 -0.175006)
			(end 0.32512 0.175006)
			(stroke
				(width 0.1)
				(type default)
			)
			(layer "F.Fab")
		)
		(fp_line
			(start -0.32512 0.175006)
			(end -0.32512 -0.175006)
			(stroke
				(width 0.1)
				(type default)
			)
			(layer "F.Fab")
		)
		(fp_line
			(start -0.32512 -0.175006)
			(end 0.32512 -0.175006)
			(stroke
				(width 0.1)
				(type default)
			)
			(layer "F.Fab")
		)
		(pad "1" smd rect
			(at -0.2667 0 180)
			(size 0.3048 0.381)
			(layers "F.Cu" "F.Mask" "F.Paste")
			(net "RT_CPU1_P2_ADDR2")
		)
		(pad "2" smd rect
			(at 0.2667 0)
			(size 0.3048 0.381)
			(layers "F.Cu" "F.Mask" "F.Paste")
			(net "GND")
		)
	)
	(footprint ""
		(layer "F.Cu")
		(at 306.388516 -438.476644 90)
		(property "Reference" "R4576"
			(at 0 0 90)
			(layer "F.SilkS")
			(hide yes)
			(effects
				(font
					(size 1.27 1.27)
				)
			)
		)
		(property "Value" ""
			(at 0 0 90)
			(layer "F.Fab")
			(effects
				(font
					(size 1.27 1.27)
				)
			)
		)
		(duplicate_pad_numbers_are_jumpers no)
		(fp_line
			(start 0.7874 -0.4064)
			(end 0.7874 0.4064)
			(stroke
				(width 0.1524)
				(type default)
			)
			(layer "F.SilkS")
		)
		(fp_line
			(start -0.7874 -0.4064)
			(end 0.7874 -0.4064)
			(stroke
				(width 0.1524)
				(type default)
			)
			(layer "F.SilkS")
		)
		(fp_line
			(start 0.7874 0.4064)
			(end -0.7874 0.4064)
			(stroke
				(width 0.1524)
				(type default)
			)
			(layer "F.SilkS")
		)
		(fp_line
			(start -0.7874 0.4064)
			(end -0.7874 -0.4064)
			(stroke
				(width 0.1524)
				(type default)
			)
			(layer "F.SilkS")
		)
		(fp_line
			(start -0.12065 -0.305054)
			(end -0.12065 -0.2794)
			(stroke
				(width 0.1)
				(type default)
			)
			(layer "F.Fab")
		)
		(fp_line
			(start -0.67945 -0.305054)
			(end -0.12065 -0.305054)
			(stroke
				(width 0.1)
				(type default)
			)
			(layer "F.Fab")
		)
		(fp_line
			(start 0.67945 -0.3048)
			(end 0.67945 0.3048)
			(stroke
				(width 0.1)
				(type default)
			)
			(layer "F.Fab")
		)
		(fp_line
			(start 0.12065 -0.3048)
			(end 0.67945 -0.3048)
			(stroke
				(width 0.1)
				(type default)
			)
			(layer "F.Fab")
		)
		(fp_line
			(start 0.12065 -0.2794)
			(end 0.12065 -0.3048)
			(stroke
				(width 0.1)
				(type default)
			)
			(layer "F.Fab")
		)
		(fp_line
			(start -0.12065 -0.2794)
			(end 0.12065 -0.2794)
			(stroke
				(width 0.1)
				(type default)
			)
			(layer "F.Fab")
		)
		(fp_line
			(start 0.120396 0.2794)
			(end -0.12065 0.2794)
			(stroke
				(width 0.1)
				(type default)
			)
			(layer "F.Fab")
		)
		(fp_line
			(start -0.12065 0.2794)
			(end -0.12065 0.3048)
			(stroke
				(width 0.1)
				(type default)
			)
			(layer "F.Fab")
		)
		(fp_line
			(start 0.67945 0.3048)
			(end 0.120396 0.3048)
			(stroke
				(width 0.1)
				(type default)
			)
			(layer "F.Fab")
		)
		(fp_line
			(start 0.120396 0.3048)
			(end 0.120396 0.2794)
			(stroke
				(width 0.1)
				(type default)
			)
			(layer "F.Fab")
		)
		(fp_line
			(start -0.12065 0.3048)
			(end -0.67945 0.3048)
			(stroke
				(width 0.1)
				(type default)
			)
			(layer "F.Fab")
		)
		(fp_line
			(start -0.67945 0.3048)
			(end -0.67945 -0.305054)
			(stroke
				(width 0.1)
				(type default)
			)
			(layer "F.Fab")
		)
		(pad "1" smd circle
			(at -0.40005 0 90)
			(size 0 0)
			(layers "F.Cu" "F.Mask" "F.Paste")
			(net "GPU_3V3IO_RSVD5_FFU")
		)
		(pad "2" smd circle
			(at 0.40005 0 90)
			(size 0 0)
			(layers "F.Cu" "F.Mask" "F.Paste")
			(net "GPU_3V3IO_RSVD5_FFU_ISO")
		)
	)
	(footprint ""
		(layer "F.Cu")
		(at 33.865058 -173.55566)
		(property "Reference" "R1335"
			(at 0 0 0)
			(layer "F.SilkS")
			(hide yes)
			(effects
				(font
					(size 1.27 1.27)
				)
			)
		)
		(property "Value" ""
			(at 0 0 0)
			(layer "F.Fab")
			(effects
				(font
					(size 1.27 1.27)
				)
			)
		)
		(duplicate_pad_numbers_are_jumpers no)
		(fp_line
			(start -0.7874 -0.4064)
			(end 0.7874 -0.4064)
			(stroke
				(width 0.1524)
				(type default)
			)
			(layer "F.SilkS")
		)
		(fp_line
			(start -0.7874 0.4064)
			(end -0.7874 -0.4064)
			(stroke
				(width 0.1524)
				(type default)
			)
			(layer "F.SilkS")
		)
		(fp_line
			(start 0.7874 -0.4064)
			(end 0.7874 0.4064)
			(stroke
				(width 0.1524)
				(type default)
			)
			(layer "F.SilkS")
		)
		(fp_line
			(start 0.7874 0.4064)
			(end -0.7874 0.4064)
			(stroke
				(width 0.1524)
				(type default)
			)
			(layer "F.SilkS")
		)
		(fp_line
			(start -0.67945 -0.305054)
			(end -0.12065 -0.305054)
			(stroke
				(width 0.1)
				(type default)
			)
			(layer "F.Fab")
		)
		(fp_line
			(start -0.67945 0.3048)
			(end -0.67945 -0.305054)
			(stroke
				(width 0.1)
				(type default)
			)
			(layer "F.Fab")
		)
		(fp_line
			(start -0.12065 -0.305054)
			(end -0.12065 -0.2794)
			(stroke
				(width 0.1)
				(type default)
			)
			(layer "F.Fab")
		)
		(fp_line
			(start -0.12065 -0.2794)
			(end 0.12065 -0.2794)
			(stroke
				(width 0.1)
				(type default)
			)
			(layer "F.Fab")
		)
		(fp_line
			(start -0.12065 0.2794)
			(end -0.12065 0.3048)
			(stroke
				(width 0.1)
				(type default)
			)
			(layer "F.Fab")
		)
		(fp_line
			(start -0.12065 0.3048)
			(end -0.67945 0.3048)
			(stroke
				(width 0.1)
				(type default)
			)
			(layer "F.Fab")
		)
		(fp_line
			(start 0.120396 0.2794)
			(end -0.12065 0.2794)
			(stroke
				(width 0.1)
				(type default)
			)
			(layer "F.Fab")
		)
		(fp_line
			(start 0.120396 0.3048)
			(end 0.120396 0.2794)
			(stroke
				(width 0.1)
				(type default)
			)
			(layer "F.Fab")
		)
		(fp_line
			(start 0.12065 -0.3048)
			(end 0.67945 -0.3048)
			(stroke
				(width 0.1)
				(type default)
			)
			(layer "F.Fab")
		)
		(fp_line
			(start 0.12065 -0.2794)
			(end 0.12065 -0.3048)
			(stroke
				(width 0.1)
				(type default)
			)
			(layer "F.Fab")
		)
		(fp_line
			(start 0.67945 -0.3048)
			(end 0.67945 0.3048)
			(stroke
				(width 0.1)
				(type default)
			)
			(layer "F.Fab")
		)
		(fp_line
			(start 0.67945 0.3048)
			(end 0.120396 0.3048)
			(stroke
				(width 0.1)
				(type default)
			)
			(layer "F.Fab")
		)
		(pad "1" smd rect
			(at -0.40005 0 180)
			(size 0.4572 0.508)
			(layers "F.Cu" "F.Mask" "F.Paste")
			(net "I3C_SPD_DDRAF_CPU1_BYPASS_SDA")
		)
		(pad "2" smd rect
			(at 0.40005 0 180)
			(size 0.4572 0.508)
			(layers "F.Cu" "F.Mask" "F.Paste")
			(net "I3C_SPD_DDRAF_CPU1_SDA")
		)
	)
)
